# T6G (Grand Teton) — schematic netlist excerpt (pin names and nets, part order shuffled) for the footprints in the layout excerpt that follows; sources: Cadence DE-HDL packaged netlist, KiCad conversion of 04192023_DAF0TMB3IC0_F0TG_MB_C_brd_V02_OCP.brd

PR398  Q_RES  0 5% CHIP  pkg 0402LF  page 226 : A = GND ; B = PVDD18_S5_P1_MODE
C760  Q_CAP_DIFFBUS  DIFF BUS_0.22UF 6.3V 20% X6S  pkg C0201  page 66 : \1\ = P5E_CPU1_P2_TX_C_DN<6> ; \2\ = P5E_CPU1_P2_TX_DN<6>
PC171  Q_CAP  2.2UF 10V 10% X6S  pkg C0402  page 206 : A = PVDDIO_P0_VCC4 ; B = GND

(kicad_pcb
	(version 20260206)
	(generator "pcbnew")
	(generator_version "10.0")
	(general
		(thickness 1.6)
		(legacy_teardrops no)
	)
	(paper "A4")
	(title_block
		(title "04192023_DAF0TMB3IC0_F0TG_MB_C_brd_V02_OCP.brd")
		(comment 1 "Grand Teton / footprints 371-373 of 8354")
	)
	(layers
		(0 "F.Cu" signal "TOP")
		(4 "In1.Cu" signal "GND")
		(6 "In2.Cu" signal "IN1")
		(8 "In3.Cu" signal "GND1")
		(10 "In4.Cu" signal "IN2")
		(12 "In5.Cu" signal "GND2")
		(14 "In6.Cu" signal "IN3")
		(16 "In7.Cu" signal "GND3")
		(18 "In8.Cu" signal "VCC")
		(20 "In9.Cu" signal "VCC1")
		(22 "In10.Cu" signal "GND4")
		(24 "In11.Cu" signal "IN4")
		(26 "In12.Cu" signal "GND5")
		(28 "In13.Cu" signal "IN5")
		(30 "In14.Cu" signal "GND6")
		(32 "In15.Cu" signal "IN6")
		(34 "In16.Cu" signal "GND7")
		(2 "B.Cu" signal "BOTTOM")
		(9 "F.Adhes" user "F.Adhesive")
		(11 "B.Adhes" user "B.Adhesive")
		(13 "F.Paste" user "Package Geometry/Pastemask Top")
		(15 "B.Paste" user "Package Geometry/Pastemask Bottom")
		(5 "F.SilkS" user "Ref Des/Silkscreen Top")
		(7 "B.SilkS" user "Ref Des/Silkscreen Bottom")
		(1 "F.Mask" user "Board Geometry/Soldermask Top")
		(3 "B.Mask" user "Board Geometry/Soldermask Bottom")
		(17 "Dwgs.User" user "User.Drawings")
		(19 "Cmts.User" user "User.Comments")
		(21 "Eco1.User" user "User.Eco1")
		(23 "Eco2.User" user "User.Eco2")
		(25 "Edge.Cuts" user "Board Geometry/Outline")
		(27 "Margin" user)
		(31 "F.CrtYd" user "Package Geometry/Place Bound Top")
		(29 "B.CrtYd" user "Package Geometry/Place Bound Bottom")
		(35 "F.Fab" user "Ref Des/Assembly Top")
		(33 "B.Fab" user "Ref Des/Assembly Bottom")
	)
	(footprint ""
		(layer "F.Cu")
		(at 271.739106 -349.381572 90)
		(property "Reference" "PC171"
			(at 0 0 90)
			(layer "F.SilkS")
			(hide yes)
			(effects
				(font
					(size 1.27 1.27)
				)
			)
		)
		(property "Value" ""
			(at 0 0 90)
			(layer "F.Fab")
			(effects
				(font
					(size 1.27 1.27)
				)
			)
		)
		(duplicate_pad_numbers_are_jumpers no)
		(fp_line
			(start 0.7874 -0.4064)
			(end 0.7874 0.4064)
			(stroke
				(width 0.1524)
				(type default)
			)
			(layer "F.SilkS")
		)
		(fp_line
			(start -0.7874 -0.4064)
			(end 0.7874 -0.4064)
			(stroke
				(width 0.1524)
				(type default)
			)
			(layer "F.SilkS")
		)
		(fp_line
			(start 0.7874 0.4064)
			(end 0.503428 0.4064)
			(stroke
				(width 0.1524)
				(type default)
			)
			(layer "F.SilkS")
		)
		(fp_line
			(start -0.258572 0.4064)
			(end -0.7874 0.4064)
			(stroke
				(width 0.1524)
				(type default)
			)
			(layer "F.SilkS")
		)
		(fp_line
			(start -0.7874 0.4064)
			(end -0.7874 -0.4064)
			(stroke
				(width 0.1524)
				(type default)
			)
			(layer "F.SilkS")
		)
		(fp_line
			(start -0.12065 -0.305054)
			(end -0.12065 -0.2794)
			(stroke
				(width 0.1)
				(type default)
			)
			(layer "F.Fab")
		)
		(fp_line
			(start -0.67945 -0.305054)
			(end -0.12065 -0.305054)
			(stroke
				(width 0.1)
				(type default)
			)
			(layer "F.Fab")
		)
		(fp_line
			(start 0.67945 -0.3048)
			(end 0.67945 0.3048)
			(stroke
				(width 0.1)
				(type default)
			)
			(layer "F.Fab")
		)
		(fp_line
			(start 0.12065 -0.3048)
			(end 0.67945 -0.3048)
			(stroke
				(width 0.1)
				(type default)
			)
			(layer "F.Fab")
		)
		(fp_line
			(start 0.12065 -0.2794)
			(end 0.12065 -0.3048)
			(stroke
				(width 0.1)
				(type default)
			)
			(layer "F.Fab")
		)
		(fp_line
			(start -0.12065 -0.2794)
			(end 0.12065 -0.2794)
			(stroke
				(width 0.1)
				(type default)
			)
			(layer "F.Fab")
		)
		(fp_line
			(start 0.120396 0.2794)
			(end -0.12065 0.2794)
			(stroke
				(width 0.1)
				(type default)
			)
			(layer "F.Fab")
		)
		(fp_line
			(start -0.12065 0.2794)
			(end -0.12065 0.3048)
			(stroke
				(width 0.1)
				(type default)
			)
			(layer "F.Fab")
		)
		(fp_line
			(start 0.67945 0.3048)
			(end 0.120396 0.3048)
			(stroke
				(width 0.1)
				(type default)
			)
			(layer "F.Fab")
		)
		(fp_line
			(start 0.120396 0.3048)
			(end 0.120396 0.2794)
			(stroke
				(width 0.1)
				(type default)
			)
			(layer "F.Fab")
		)
		(fp_line
			(start -0.12065 0.3048)
			(end -0.67945 0.3048)
			(stroke
				(width 0.1)
				(type default)
			)
			(layer "F.Fab")
		)
		(fp_line
			(start -0.67945 0.3048)
			(end -0.67945 -0.305054)
			(stroke
				(width 0.1)
				(type default)
			)
			(layer "F.Fab")
		)
		(pad "1" smd circle
			(at -0.40005 0 90)
			(size 0 0)
			(layers "F.Cu" "F.Mask" "F.Paste")
			(net "PVDDIO_P0_VCC4")
		)
		(pad "2" smd circle
			(at 0.40005 0 90)
			(size 0 0)
			(layers "F.Cu" "F.Mask" "F.Paste")
			(net "GND")
		)
	)
	(footprint ""
		(layer "F.Cu")
		(at 152.040844 -370.57203 -90)
		(property "Reference" "C760"
			(at 0 0 270)
			(layer "F.SilkS")
			(hide yes)
			(effects
				(font
					(size 1.27 1.27)
				)
			)
		)
		(property "Value" ""
			(at 0 0 270)
			(layer "F.Fab")
			(effects
				(font
					(size 1.27 1.27)
				)
			)
		)
		(duplicate_pad_numbers_are_jumpers no)
		(fp_line
			(start -0.299974 0.150114)
			(end -0.299974 -0.150114)
			(stroke
				(width 0.1)
				(type default)
			)
			(layer "F.Fab")
		)
		(fp_line
			(start 0.299974 0.150114)
			(end -0.299974 0.150114)
			(stroke
				(width 0.1)
				(type default)
			)
			(layer "F.Fab")
		)
		(fp_line
			(start -0.299974 -0.150114)
			(end 0.299974 -0.150114)
			(stroke
				(width 0.1)
				(type default)
			)
			(layer "F.Fab")
		)
		(fp_line
			(start 0.299974 -0.150114)
			(end 0.299974 0.150114)
			(stroke
				(width 0.1)
				(type default)
			)
			(layer "F.Fab")
		)
		(pad "1" smd rect
			(at -0.2667 0 270)
			(size 0.3048 0.381)
			(layers "F.Cu" "F.Mask" "F.Paste")
			(net "P5E_CPU1_P2_TX_C_DN<6>")
		)
		(pad "2" smd rect
			(at 0.2667 0 270)
			(size 0.3048 0.381)
			(layers "F.Cu" "F.Mask" "F.Paste")
			(net "P5E_CPU1_P2_TX_DN<6>")
		)
	)
	(footprint ""
		(layer "F.Cu")
		(at 69.359526 -148.22678 90)
		(property "Reference" "PR398"
			(at 0 0 90)
			(layer "F.SilkS")
			(hide yes)
			(effects
				(font
					(size 1.27 1.27)
				)
			)
		)
		(property "Value" ""
			(at 0 0 90)
			(layer "F.Fab")
			(effects
				(font
					(size 1.27 1.27)
				)
			)
		)
		(duplicate_pad_numbers_are_jumpers no)
		(fp_line
			(start 0.7874 -0.4064)
			(end 0.7874 0.4064)
			(stroke
				(width 0.1524)
				(type default)
			)
			(layer "F.SilkS")
		)
		(fp_line
			(start -0.7874 -0.4064)
			(end 0.7874 -0.4064)
			(stroke
				(width 0.1524)
				(type default)
			)
			(layer "F.SilkS")
		)
		(fp_line
			(start 0.7874 0.4064)
			(end -0.7874 0.4064)
			(stroke
				(width 0.1524)
				(type default)
			)
			(layer "F.SilkS")
		)
		(fp_line
			(start -0.7874 0.4064)
			(end -0.7874 -0.4064)
			(stroke
				(width 0.1524)
				(type default)
			)
			(layer "F.SilkS")
		)
		(fp_line
			(start -0.12065 -0.305054)
			(end -0.12065 -0.2794)
			(stroke
				(width 0.1)
				(type default)
			)
			(layer "F.Fab")
		)
		(fp_line
			(start -0.67945 -0.305054)
			(end -0.12065 -0.305054)
			(stroke
				(width 0.1)
				(type default)
			)
			(layer "F.Fab")
		)
		(fp_line
			(start 0.67945 -0.3048)
			(end 0.67945 0.3048)
			(stroke
				(width 0.1)
				(type default)
			)
			(layer "F.Fab")
		)
		(fp_line
			(start 0.12065 -0.3048)
			(end 0.67945 -0.3048)
			(stroke
				(width 0.1)
				(type default)
			)
			(layer "F.Fab")
		)
		(fp_line
			(start 0.12065 -0.2794)
			(end 0.12065 -0.3048)
			(stroke
				(width 0.1)
				(type default)
			)
			(layer "F.Fab")
		)
		(fp_line
			(start -0.12065 -0.2794)
			(end 0.12065 -0.2794)
			(stroke
				(width 0.1)
				(type default)
			)
			(layer "F.Fab")
		)
		(fp_line
			(start 0.120396 0.2794)
			(end -0.12065 0.2794)
			(stroke
				(width 0.1)
				(type default)
			)
			(layer "F.Fab")
		)
		(fp_line
			(start -0.12065 0.2794)
			(end -0.12065 0.3048)
			(stroke
				(width 0.1)
				(type default)
			)
			(layer "F.Fab")
		)
		(fp_line
			(start 0.67945 0.3048)
			(end 0.120396 0.3048)
			(stroke
				(width 0.1)
				(type default)
			)
			(layer "F.Fab")
		)
		(fp_line
			(start 0.120396 0.3048)
			(end 0.120396 0.2794)
			(stroke
				(width 0.1)
				(type default)
			)
			(layer "F.Fab")
		)
		(fp_line
			(start -0.12065 0.3048)
			(end -0.67945 0.3048)
			(stroke
				(width 0.1)
				(type default)
			)
			(layer "F.Fab")
		)
		(fp_line
			(start -0.67945 0.3048)
			(end -0.67945 -0.305054)
			(stroke
				(width 0.1)
				(type default)
			)
			(layer "F.Fab")
		)
		(pad "1" smd circle
			(at -0.40005 0 90)
			(size 0 0)
			(layers "F.Cu" "F.Mask" "F.Paste")
			(net "GND")
		)
		(pad "2" smd circle
			(at 0.40005 0 90)
			(size 0 0)
			(layers "F.Cu" "F.Mask" "F.Paste")
			(net "PVDD18_S5_P1_MODE")
		)
	)
)
